(kicad_pcb
	(version 20221018)
	(generator pcbnew)
	(general
    (thickness 1.518)
  )
	(paper "A4")
	(title_block
    (title "Kria K26 Devboard")
    (date "2024-03-26")
    (rev "1.2.5")
    (comment 1 "www.antmicro.com")
    (comment 2 "Antmicro Ltd.")
		(comment 9 "footprints 122-126 of 660")
	)
	(layers
    (0 "F.Cu" mixed)
    (1 "In1.Cu" power)
    (2 "In2.Cu" mixed)
    (3 "In3.Cu" power)
    (4 "In4.Cu" mixed)
    (5 "In5.Cu" power)
    (6 "In6.Cu" mixed)
    (31 "B.Cu" power)
    (32 "B.Adhes" user "B.Adhesive")
    (33 "F.Adhes" user "F.Adhesive")
    (34 "B.Paste" user)
    (35 "F.Paste" user)
    (36 "B.SilkS" user "B.Silkscreen")
    (37 "F.SilkS" user "F.Silkscreen")
    (38 "B.Mask" user)
    (39 "F.Mask" user)
    (40 "Dwgs.User" user "User.Drawings")
    (41 "Cmts.User" user "User.Comments")
    (42 "Eco1.User" user "User.Eco1")
    (43 "Eco2.User" user "User.Eco2")
    (44 "Edge.Cuts" user)
    (45 "Margin" user)
    (46 "B.CrtYd" user "B.Courtyard")
    (47 "F.CrtYd" user "F.Courtyard")
    (48 "B.Fab" user)
    (49 "F.Fab" user)
  )
	(footprint "kria-k26-devboard-footprints:UQFN-16-1.8x2.6mm_P0.4mm_Texas_RSV0016A" (layer "F.Cu")
    (at 139.425 121.2 90)
    (descr "https://www.ti.com/lit/ds/symlink/sn74avch4t245-ep.pdf?ts=1679484181203&ref_url=https%253A%252F%252Fwww.ti.com%252Fproduct%252FSN74AVCH4T245-EP%253Futm_source%253Dgoogle%2526utm_medium%253Dcpc%2526utm_campaign%253Dasc-int-null-prodfolderdynamic-cpc-pf-google-wwe_int%2526utm_content%253Dprodfolddynamic%2526ds_k%253DDYNAMIC%2BSEARCH%2BADS%2526DCM%253Dyes%2526gclid%253DCjwKCAjwzuqgBhAcEiwAdj5dRvR_WgyvqqhLxMx8zfbFv2a6tg33JIMv01Bn4M1kA4JzW1nDDW7OzhoCRbkQAvD_BwE%2526gclsrc%253Daw.ds")
    (property "Author" "Antmicro")
    (property "License" "Apache-2.0")
    (property "MPN" "74AVC4T245RSVRG4")
    (property "Manufacturer" "Texas Instruments")
    (property "Sheetfile" "debug.kicad_sch")
    (property "Sheetname" "Debug and JTAG")
    (property "ki_description" "Logic translator/level shifter")
    (property "ki_keywords" "SMT, LOGIC, IC, LEVEL-SHIFTER")
    (attr smd)
    (fp_text reference "U43" (at 1.37 -2.055 180) (layer "F.SilkS")
        (effects (font (size 0.7 0.7) (thickness 0.15)) (justify left bottom))
    )
    (fp_text value "74AVC4T245_UQFN" (at -1.25 2.5 90) (layer "F.Fab") hide
        (effects (font (size 0.7 0.7) (thickness 0.15)) (justify left bottom))
    )
    (fp_text user "." (at -1.45 -0.75 90) (layer "F.SilkS")
        (effects (font (size 0.7 0.7) (thickness 0.15)) (justify left bottom))
    )
    (fp_text user "License: Apache-2.0" (at -1.25 6.25 90) (layer "F.Fab") hide
        (effects (font (size 0.7 0.7) (thickness 0.15)) (justify left bottom))
    )
    (fp_text user "Author: Antmicro" (at -1.25 5 90) (layer "F.Fab") hide
        (effects (font (size 0.7 0.7) (thickness 0.15)) (justify left bottom))
    )
    (fp_text user "${REFERENCE}" (at -1.25 3.75 90) (layer "F.Fab") hide
        (effects (font (size 0.7 0.7) (thickness 0.15)) (justify left bottom))
    )
    (fp_line (start -0.9 1.2995) (end -0.9 0.8)
      (stroke (width 0.15) (type solid)) (layer "F.SilkS"))
    (fp_line (start -0.8 -1.3) (end -0.9 -1.3)
      (stroke (width 0.15) (type solid)) (layer "F.SilkS"))
    (fp_line (start -0.8 1.2995) (end -0.9 1.2995)
      (stroke (width 0.15) (type solid)) (layer "F.SilkS"))
    (fp_line (start 0.8 -1.3) (end 0.9 -1.3)
      (stroke (width 0.15) (type solid)) (layer "F.SilkS"))
    (fp_line (start 0.8 1.3) (end 0.899 1.3)
      (stroke (width 0.15) (type solid)) (layer "F.SilkS"))
    (fp_line (start 0.9 -1.3) (end 0.9 -0.8005)
      (stroke (width 0.15) (type solid)) (layer "F.SilkS"))
    (fp_line (start 0.9 0.8) (end 0.899 1.3)
      (stroke (width 0.15) (type solid)) (layer "F.SilkS"))
    (fp_rect (start -1.25 -1.65) (end 1.25 1.65)
      (stroke (width 0.05) (type solid)) (fill none) (layer "F.CrtYd"))
    (fp_line (start -0.902 1.3) (end -0.902 -1.301)
      (stroke (width 0.15) (type solid)) (layer "F.Fab"))
    (fp_line (start 0.9 -1.301) (end -0.902 -1.301)
      (stroke (width 0.15) (type solid)) (layer "F.Fab"))
    (fp_line (start 0.9 1.3) (end -0.902 1.3)
      (stroke (width 0.15) (type solid)) (layer "F.Fab"))
    (fp_line (start 0.9 1.3) (end 0.9 -1.301)
      (stroke (width 0.15) (type solid)) (layer "F.Fab"))
    (pad "1" smd roundrect (at -0.75 -0.6 90) (size 0.7 0.2) (layers "F.Cu" "F.Paste" "F.Mask") (roundrect_rratio 0.2272727273)
      (net 160 "/Debug and JTAG/~{LS_OE}") (pinfunction "1~{OE}") (pintype "input"))
    (pad "2" smd roundrect (at -0.802 -0.202 90) (size 0.6 0.2) (layers "F.Cu" "F.Paste" "F.Mask") (roundrect_rratio 0.2272727273)
      (net 17 "PS_1V8") (pinfunction "VCCB") (pintype "power_in"))
    (pad "3" smd roundrect (at -0.802 0.2 90) (size 0.6 0.2) (layers "F.Cu" "F.Paste" "F.Mask") (roundrect_rratio 0.2272727273)
      (net 138 "/Debug and JTAG/USB_3V3") (pinfunction "VCCA") (pintype "power_in"))
    (pad "4" smd roundrect (at -0.802 0.598 90) (size 0.6 0.2) (layers "F.Cu" "F.Paste" "F.Mask") (roundrect_rratio 0.2272727273)
      (net 1 "GND") (pinfunction "1DIR") (pintype "input"))
    (pad "5" smd roundrect (at -0.6 1.199 180) (size 0.6 0.2) (layers "F.Cu" "F.Paste" "F.Mask") (roundrect_rratio 0.2272727273)
      (net 1 "GND") (pinfunction "2DIR") (pintype "input"))
    (pad "6" smd roundrect (at -0.202 1.199 180) (size 0.6 0.2) (layers "F.Cu" "F.Paste" "F.Mask") (roundrect_rratio 0.2272727273)
      (net 171 "/Debug and JTAG/FTDI_TDO") (pinfunction "1A1") (pintype "bidirectional"))
    (pad "7" smd roundrect (at 0.2 1.199 180) (size 0.6 0.2) (layers "F.Cu" "F.Paste" "F.Mask") (roundrect_rratio 0.2272727273)
      (net 777 "unconnected-(U43-1A2-Pad7)") (pinfunction "1A2") (pintype "bidirectional+no_connect"))
    (pad "8" smd roundrect (at 0.598 1.199 180) (size 0.6 0.2) (layers "F.Cu" "F.Paste" "F.Mask") (roundrect_rratio 0.2272727273)
      (net 169 "/Debug and JTAG/JTAG_VCCO_ON") (pinfunction "2A1") (pintype "bidirectional"))
    (pad "9" smd roundrect (at 0.8 0.598 90) (size 0.6 0.2) (layers "F.Cu" "F.Paste" "F.Mask") (roundrect_rratio 0.2272727273)
      (net 778 "unconnected-(U43-2A2-Pad9)") (pinfunction "2A2") (pintype "bidirectional+no_connect"))
    (pad "10" smd roundrect (at 0.8 0.2 90) (size 0.6 0.2) (layers "F.Cu" "F.Paste" "F.Mask") (roundrect_rratio 0.2272727273)
      (net 1 "GND") (pinfunction "GND") (pintype "power_in"))
    (pad "11" smd roundrect (at 0.8 -0.202 90) (size 0.6 0.2) (layers "F.Cu" "F.Paste" "F.Mask") (roundrect_rratio 0.2272727273)
      (net 1 "GND") (pinfunction "GND") (pintype "passive"))
    (pad "12" smd roundrect (at 0.8 -0.6 90) (size 0.6 0.2) (layers "F.Cu" "F.Paste" "F.Mask") (roundrect_rratio 0.2272727273)
      (net 1 "GND") (pinfunction "2B2") (pintype "bidirectional"))
    (pad "13" smd roundrect (at 0.598 -1.2 180) (size 0.6 0.2) (layers "F.Cu" "F.Paste" "F.Mask") (roundrect_rratio 0.2272727273)
      (net 17 "PS_1V8") (pinfunction "2B1") (pintype "bidirectional"))
    (pad "14" smd roundrect (at 0.2 -1.2 180) (size 0.6 0.2) (layers "F.Cu" "F.Paste" "F.Mask") (roundrect_rratio 0.2272727273)
      (net 1 "GND") (pinfunction "1B2") (pintype "bidirectional"))
    (pad "15" smd roundrect (at -0.202 -1.2 180) (size 0.6 0.2) (layers "F.Cu" "F.Paste" "F.Mask") (roundrect_rratio 0.2272727273)
      (net 142 "/Debug and JTAG/JTAG_TDO_M2C") (pinfunction "1B1") (pintype "bidirectional"))
    (pad "16" smd roundrect (at -0.6 -1.2 180) (size 0.6 0.2) (layers "F.Cu" "F.Paste" "F.Mask") (roundrect_rratio 0.2272727273)
      (net 1 "GND") (pinfunction "2~{OE}") (pintype "input"))
  )
	(footprint "kria-k26-devboard-footprints:C_0402_1005Metric" (layer "F.Cu")
    (at 147.83 125.86 -90)
    (descr "Capacitor SMD 0402")
    (tags "capacitor SMD 0402")
    (property "Author" "Antmicro")
    (property "Dielectric" "")
    (property "License" "Apache-2.0")
    (property "MPN" "MC0402N180J500CT")
    (property "Manufacturer" "Multicomp")
    (property "Sheetfile" "debug.kicad_sch")
    (property "Sheetname" "Debug and JTAG")
    (property "Val" "18p")
    (property "Voltage" "")
    (property "ki_description" " ")
    (attr smd)
    (fp_text reference "C154" (at 1.42 0.52 -90) (layer "F.SilkS")
        (effects (font (size 0.7 0.7) (thickness 0.15)) (justify left bottom))
    )
    (fp_text value "C_18p_0402" (at 0 1.4 -90) (layer "F.Fab") hide
        (effects (font (size 0.7 0.7) (thickness 0.15)) (justify left bottom))
    )
    (fp_text user "Author: Antmicro" (at -0.932 4.17 -90) (layer "F.Fab") hide
        (effects (font (size 0.7 0.7) (thickness 0.15)) (justify left bottom))
    )
    (fp_text user "${REFERENCE}" (at -0.932 3.168 -90) (layer "F.Fab") hide
        (effects (font (size 0.7 0.7) (thickness 0.15)) (justify left bottom))
    )
    (fp_text user "License: Apache-2.0" (at -0.932 5.17 -90) (layer "F.Fab") hide
        (effects (font (size 0.7 0.7) (thickness 0.15)) (justify left bottom))
    )
    (fp_rect (start -0.94 -0.47) (end 0.94 0.47)
      (stroke (width 0.05) (type solid)) (fill none) (layer "F.CrtYd"))
    (fp_rect (start -0.499 -0.249) (end 0.499 0.249)
      (stroke (width 0.15) (type solid)) (fill none) (layer "F.Fab"))
    (pad "1" smd roundrect (at -0.484 0 270) (size 0.59 0.64) (layers "F.Cu" "F.Paste" "F.Mask") (roundrect_rratio 0.25)
      (net 137 "/Debug and JTAG/XIN") (pintype "passive"))
    (pad "2" smd roundrect (at 0.484 0 270) (size 0.59 0.64) (layers "F.Cu" "F.Paste" "F.Mask") (roundrect_rratio 0.25)
      (net 1 "GND") (pintype "passive"))
  )
	(footprint "kria-k26-devboard-footprints:LED_0603_1608Metric_G" (layer "F.Cu")
    (at 139.45 94.4 -90)
    (descr "LED SMD 0603 Green")
    (tags "LED SMD 0603 Green")
    (property "Author" "Antmicro")
    (property "Color" "Green")
    (property "License" "Apache-2.0")
    (property "MPN" "LG L29K-G2J1-24-Z")
    (property "Manufacturer" "OSRAM")
    (property "Sheetfile" "dc-dc-conventers.kicad_sch")
    (property "Sheetname" "DC/DC conventers")
    (property "ki_description" "LED, Green, SMT, 0603, 20 mA, 2.1 V, 570 nm")
    (property "ki_keywords" "0603, SMT, DIODE, SEMICONDUCTOR, UNICOLOR")
    (attr smd)
    (fp_text reference "D18" (at -0.97 -1.31 90) (layer "F.SilkS")
        (effects (font (size 0.7 0.7) (thickness 0.15)) (justify right bottom))
    )
    (fp_text value "LED_G_0603_LG_L29K-G2J1-24-Z" (at 0 1.6 90) (layer "F.Fab") hide
        (effects (font (size 0.7 0.7) (thickness 0.15)) (justify right bottom))
    )
    (fp_text user "License: Apache-2.0" (at -1.31 5.769 90) (layer "F.Fab") hide
        (effects (font (size 0.7 0.7) (thickness 0.15)) (justify right bottom))
    )
    (fp_text user "Author: Antmicro" (at -1.31 4.769 90) (layer "F.Fab") hide
        (effects (font (size 0.7 0.7) (thickness 0.15)) (justify right bottom))
    )
    (fp_text user "${REFERENCE}" (at -1.31 3.769 90) (layer "F.Fab") hide
        (effects (font (size 0.7 0.7) (thickness 0.15)) (justify right bottom))
    )
    (fp_line (start -0.27 -0.35) (end 0.27 -0.35)
      (stroke (width 0.15) (type solid)) (layer "F.SilkS"))
    (fp_line (start -0.27 0.351) (end 0.27 0.351)
      (stroke (width 0.15) (type solid)) (layer "F.SilkS"))
    (fp_line (start -0.106328 -0.200008) (end -0.106328 0.199992)
      (stroke (width 0.1) (type solid)) (layer "F.SilkS"))
    (fp_line (start -0.106328 -0.200008) (end 0.093672 -0.000008)
      (stroke (width 0.1) (type solid)) (layer "F.SilkS"))
    (fp_line (start -0.106328 -0.000008) (end -0.29 0)
      (stroke (width 0.1) (type solid)) (layer "F.SilkS"))
    (fp_line (start 0.093672 -0.200008) (end 0.093672 0.199992)
      (stroke (width 0.1) (type solid)) (layer "F.SilkS"))
    (fp_line (start 0.093672 -0.000008) (end -0.106328 0.199992)
      (stroke (width 0.1) (type solid)) (layer "F.SilkS"))
    (fp_line (start 0.093672 -0.000008) (end 0.293672 -0.000008)
      (stroke (width 0.1) (type solid)) (layer "F.SilkS"))
    (fp_line (start 1.25 0.32) (end 1.25 -0.32)
      (stroke (width 0.15) (type solid)) (layer "F.SilkS"))
    (fp_rect (start 1.26 0.65) (end -1.26 -0.65)
      (stroke (width 0.05) (type solid)) (fill none) (layer "F.CrtYd"))
    (fp_line (start -0.599 0) (end -0.201 0)
      (stroke (width 0.15) (type solid)) (layer "F.Fab"))
    (fp_line (start -0.201 -0.2) (end -0.201 0)
      (stroke (width 0.15) (type solid)) (layer "F.Fab"))
    (fp_line (start -0.201 0) (end -0.201 0.202)
      (stroke (width 0.15) (type solid)) (layer "F.Fab"))
    (fp_line (start -0.201 0.202) (end 0.101 0)
      (stroke (width 0.15) (type solid)) (layer "F.Fab"))
    (fp_line (start 0.101 0) (end -0.201 -0.2)
      (stroke (width 0.15) (type solid)) (layer "F.Fab"))
    (fp_line (start 0.199 -0.2) (end 0.199 -0.1)
      (stroke (width 0.15) (type solid)) (layer "F.Fab"))
    (fp_line (start 0.199 0) (end 0.597 0)
      (stroke (width 0.15) (type solid)) (layer "F.Fab"))
    (fp_line (start 0.199 0.202) (end 0.199 -0.1)
      (stroke (width 0.15) (type solid)) (layer "F.Fab"))
    (fp_rect (start -0.848 -0.4) (end 0.85 0.402)
      (stroke (width 0.15) (type solid)) (fill none) (layer "F.Fab"))
    (pad "1" smd rect (at -0.75 0 90) (size 0.8 0.8) (layers "F.Cu" "F.Paste" "F.Mask")
      (net 190 "Net-(D18-Pad1)") (pintype "passive"))
    (pad "2" smd rect (at 0.75 0 90) (size 0.8 0.8) (layers "F.Cu" "F.Paste" "F.Mask")
      (net 339 "Net-(Q14-C)") (pinfunction "2") (pintype "passive"))
  )
	(footprint "kria-k26-devboard-footprints:SOT-416" (layer "F.Cu")
    (at 149.382843 129.183096 -90)
    (descr "SOT-416")
    (tags "SOT-416")
    (property "Author" "Antmicro")
    (property "License" "Apache-2.0")
    (property "MPN" "DTC014TEBTL")
    (property "Manufacturer" "ROHM Semiconductor")
    (property "Sheetfile" "debug.kicad_sch")
    (property "Sheetname" "Debug and JTAG")
    (property "ki_description" "Digital NPN Transistor, 10k/NONE, EMT-3")
    (attr smd)
    (fp_text reference "Q12" (at 1.796904 1.162843) (layer "F.SilkS")
        (effects (font (size 0.7 0.7) (thickness 0.15)) (justify left bottom))
    )
    (fp_text value "DTC014T_SOT-416" (at 0 2 -90) (layer "F.Fab") hide
        (effects (font (size 0.7 0.7) (thickness 0.15)) (justify left bottom))
    )
    (fp_text user "Author: Antmicro" (at -1 4.602 -90) (layer "F.Fab") hide
        (effects (font (size 0.7 0.7) (thickness 0.15)) (justify left bottom))
    )
    (fp_text user "${REFERENCE}" (at -1 3.4 -90) (layer "F.Fab") hide
        (effects (font (size 0.7 0.7) (thickness 0.15)) (justify left bottom))
    )
    (fp_text user "License: Apache-2.0" (at -1 5.802 -90) (layer "F.Fab") hide
        (effects (font (size 0.7 0.7) (thickness 0.15)) (justify left bottom))
    )
    (fp_line (start -0.5 -0.15) (end -0.5 0.15)
      (stroke (width 0.15) (type solid)) (layer "F.SilkS"))
    (fp_line (start 0.5 0.9) (end -0.5 0.9)
      (stroke (width 0.15) (type solid)) (layer "F.SilkS"))
    (fp_line (start 0.5 0.9) (end 0.5 0.7)
      (stroke (width 0.15) (type solid)) (layer "F.SilkS"))
    (fp_line (start 0.508 -0.9) (end -0.5 -0.9)
      (stroke (width 0.15) (type solid)) (layer "F.SilkS"))
    (fp_line (start 0.508 -0.9) (end 0.508 -0.592)
      (stroke (width 0.15) (type solid)) (layer "F.SilkS"))
    (fp_rect (start -1 -1.05) (end 1 1.05)
      (stroke (width 0.05) (type solid)) (fill none) (layer "F.CrtYd"))
    (fp_line (start -0.05 -0.9) (end -0.45 -0.5)
      (stroke (width 0.15) (type solid)) (layer "F.Fab"))
    (fp_rect (start 0.45 0.9) (end -0.45 -0.9)
      (stroke (width 0.15) (type solid)) (fill none) (layer "F.Fab"))
    (pad "1" smd rect (at -0.652 -0.5 270) (size 0.6 0.5) (layers "F.Cu" "F.Paste" "F.Mask")
      (net 158 "/Debug and JTAG/FTDI_EEPROM_WC") (pinfunction "B") (pintype "input"))
    (pad "2" smd rect (at -0.652 0.498 270) (size 0.6 0.5) (layers "F.Cu" "F.Paste" "F.Mask")
      (net 1 "GND") (pinfunction "E") (pintype "passive"))
    (pad "3" smd rect (at 0.65 0 270) (size 0.6 0.5) (layers "F.Cu" "F.Paste" "F.Mask")
      (net 186 "/Debug and JTAG/~{EEPROM_WC}") (pinfunction "C") (pintype "passive"))
  )
	(footprint "kria-k26-devboard-footprints:R_0402_1005Metric" (layer "F.Cu")
    (at 148.225 110 -90)
    (descr "Resistor SMD 0402")
    (tags "resistor SMD 0402")
    (property "Author" "Antmicro")
    (property "Current" "1A")
    (property "DNP" "DNP")
    (property "License" "Apache-2.0")
    (property "MPN" "ERJ2GE0R00X")
    (property "Manufacturer" "Panasonic")
    (property "Sheetfile" "debug.kicad_sch")
    (property "Sheetname" "Debug and JTAG")
    (property "Tolerance" "")
    (property "Val" "0R")
    (property "dnp" "")
    (property "exclude_from_bom" "")
    (property "ki_description" "0R resistor in 0402 package with unspecified tolerance")
    (attr exclude_from_pos_files exclude_from_bom)
    (fp_text reference "R101" (at -3.22 -0.365 -90) (layer "F.SilkS")
        (effects (font (size 0.7 0.7) (thickness 0.15)) (justify left bottom))
    )
    (fp_text value "R_0R_0402" (at 0 1.4 -90) (layer "F.Fab") hide
        (effects (font (size 0.7 0.7) (thickness 0.15)) (justify left bottom))
    )
    (fp_text user "License: Apache-2.0" (at -0.95 5.169 -90) (layer "F.Fab") hide
        (effects (font (size 0.7 0.7) (thickness 0.15)) (justify left bottom))
    )
    (fp_text user "${REFERENCE}" (at -0.95 3.168 -90) (layer "F.Fab") hide
        (effects (font (size 0.7 0.7) (thickness 0.15)) (justify left bottom))
    )
    (fp_text user "Author: Antmicro" (at -0.95 4.169 -90) (layer "F.Fab") hide
        (effects (font (size 0.7 0.7) (thickness 0.15)) (justify left bottom))
    )
    (fp_rect (start -0.93 -0.47) (end 0.93 0.47)
      (stroke (width 0.05) (type solid)) (fill none) (layer "F.CrtYd"))
    (fp_rect (start -0.5 -0.25) (end 0.5 0.25)
      (stroke (width 0.15) (type solid)) (fill none) (layer "F.Fab"))
    (pad "1" smd roundrect (at -0.485 0 270) (size 0.59 0.64) (layers "F.Cu" "F.Paste" "F.Mask") (roundrect_rratio 0.25)
      (net 234 "/Debug and JTAG/USB_N") (pintype "passive"))
    (pad "2" smd roundrect (at 0.485 0 270) (size 0.59 0.64) (layers "F.Cu" "F.Paste" "F.Mask") (roundrect_rratio 0.25)
      (net 223 "/Debug and JTAG/USBB_N") (pintype "passive"))
  )
)
